(kicad_pcb
	(version 20260206)
	(generator "pcbnew")
	(generator_version "10.0")
	(general
		(thickness 1.6)
		(legacy_teardrops no)
	)
	(paper "A4")
	(title_block
		(title "04192023_DAF0TMB3IC0_F0TG_MB_C_brd_V02_OCP.brd")
		(comment 1 "Grand Teton / footprints 156-164 of 8354")
	)
	(layers
		(0 "F.Cu" signal "TOP")
		(4 "In1.Cu" signal "GND")
		(6 "In2.Cu" signal "IN1")
		(8 "In3.Cu" signal "GND1")
		(10 "In4.Cu" signal "IN2")
		(12 "In5.Cu" signal "GND2")
		(14 "In6.Cu" signal "IN3")
		(16 "In7.Cu" signal "GND3")
		(18 "In8.Cu" signal "VCC")
		(20 "In9.Cu" signal "VCC1")
		(22 "In10.Cu" signal "GND4")
		(24 "In11.Cu" signal "IN4")
		(26 "In12.Cu" signal "GND5")
		(28 "In13.Cu" signal "IN5")
		(30 "In14.Cu" signal "GND6")
		(32 "In15.Cu" signal "IN6")
		(34 "In16.Cu" signal "GND7")
		(2 "B.Cu" signal "BOTTOM")
		(9 "F.Adhes" user "F.Adhesive")
		(11 "B.Adhes" user "B.Adhesive")
		(13 "F.Paste" user "Package Geometry/Pastemask Top")
		(15 "B.Paste" user "Package Geometry/Pastemask Bottom")
		(5 "F.SilkS" user "Ref Des/Silkscreen Top")
		(7 "B.SilkS" user "Ref Des/Silkscreen Bottom")
		(1 "F.Mask" user "Board Geometry/Soldermask Top")
		(3 "B.Mask" user "Board Geometry/Soldermask Bottom")
		(17 "Dwgs.User" user "User.Drawings")
		(19 "Cmts.User" user "User.Comments")
		(21 "Eco1.User" user "User.Eco1")
		(23 "Eco2.User" user "User.Eco2")
		(25 "Edge.Cuts" user "Board Geometry/Outline")
		(27 "Margin" user)
		(31 "F.CrtYd" user "Package Geometry/Place Bound Top")
		(29 "B.CrtYd" user "Package Geometry/Place Bound Bottom")
		(35 "F.Fab" user "Ref Des/Assembly Top")
		(33 "B.Fab" user "Ref Des/Assembly Bottom")
	)
	(footprint ""
		(layer "F.Cu")
		(at 68.16852 -395.6304 -90)
		(property "Reference" "R6708"
			(at 0 0 270)
			(layer "F.SilkS")
			(hide yes)
			(effects
				(font
					(size 1.27 1.27)
				)
			)
		)
		(property "Value" ""
			(at 0 0 270)
			(layer "F.Fab")
			(effects
				(font
					(size 1.27 1.27)
				)
			)
		)
		(duplicate_pad_numbers_are_jumpers no)
		(fp_line
			(start -0.32512 0.175006)
			(end -0.32512 -0.175006)
			(stroke
				(width 0.1)
				(type default)
			)
			(layer "F.Fab")
		)
		(fp_line
			(start 0.32512 0.175006)
			(end -0.32512 0.175006)
			(stroke
				(width 0.1)
				(type default)
			)
			(layer "F.Fab")
		)
		(fp_line
			(start -0.32512 -0.175006)
			(end 0.32512 -0.175006)
			(stroke
				(width 0.1)
				(type default)
			)
			(layer "F.Fab")
		)
		(fp_line
			(start 0.32512 -0.175006)
			(end 0.32512 0.175006)
			(stroke
				(width 0.1)
				(type default)
			)
			(layer "F.Fab")
		)
		(pad "1" smd rect
			(at -0.2667 0 270)
			(size 0.3048 0.381)
			(layers "F.Cu" "F.Mask" "F.Paste")
			(net "RST_RT_CPU1_P0_PERST_N")
		)
		(pad "2" smd rect
			(at 0.2667 0 90)
			(size 0.3048 0.381)
			(layers "F.Cu" "F.Mask" "F.Paste")
			(net "RST_RT_CPU1_P0_PERST_R_N")
		)
	)
	(footprint ""
		(layer "F.Cu")
		(at 359.297986 -332.580996 90)
		(property "Reference" "PL9"
			(at -3.302 4.149852 90)
			(unlocked yes)
			(layer "F.SilkS")
			(effects
				(font
					(size 0.7874 0.5842)
					(thickness 0.1524)
				)
				(justify left)
			)
		)
		(property "Value" ""
			(at 0 0 90)
			(layer "F.Fab")
			(effects
				(font
					(size 1.27 1.27)
				)
			)
		)
		(duplicate_pad_numbers_are_jumpers no)
		(fp_line
			(start 3.24993 -3.24993)
			(end 3.24993 -2.2352)
			(stroke
				(width 0.1524)
				(type default)
			)
			(layer "F.SilkS")
		)
		(fp_line
			(start -3.24993 -3.24993)
			(end 3.24993 -3.24993)
			(stroke
				(width 0.1524)
				(type default)
			)
			(layer "F.SilkS")
		)
		(fp_line
			(start -3.24993 -2.2352)
			(end -3.24993 -3.24993)
			(stroke
				(width 0.1524)
				(type default)
			)
			(layer "F.SilkS")
		)
		(fp_line
			(start 3.24993 2.2352)
			(end 3.24993 3.24993)
			(stroke
				(width 0.1524)
				(type default)
			)
			(layer "F.SilkS")
		)
		(fp_line
			(start 3.24993 3.24993)
			(end -3.24993 3.24993)
			(stroke
				(width 0.1524)
				(type default)
			)
			(layer "F.SilkS")
		)
		(fp_line
			(start -3.24993 3.24993)
			(end -3.24993 2.2352)
			(stroke
				(width 0.1524)
				(type default)
			)
			(layer "F.SilkS")
		)
		(fp_line
			(start 3.24993 -3.24993)
			(end 3.24993 3.24993)
			(stroke
				(width 0.1)
				(type default)
			)
			(layer "F.Fab")
		)
		(fp_line
			(start -3.24993 -3.24993)
			(end 3.24993 -3.24993)
			(stroke
				(width 0.1)
				(type default)
			)
			(layer "F.Fab")
		)
		(fp_line
			(start 3.24993 3.24993)
			(end -3.24993 3.24993)
			(stroke
				(width 0.1)
				(type default)
			)
			(layer "F.Fab")
		)
		(fp_line
			(start -3.24993 3.24993)
			(end -3.24993 -3.24993)
			(stroke
				(width 0.1)
				(type default)
			)
			(layer "F.Fab")
		)
		(pad "1" smd rect
			(at -2.29997 0 90)
			(size 2.0066 4.2164)
			(layers "F.Cu" "F.Mask" "F.Paste")
			(net "IND_CPU1_P0_CPL0")
		)
		(pad "2" smd rect
			(at 2.29997 0 90)
			(size 2.0066 4.2164)
			(layers "F.Cu" "F.Mask" "F.Paste")
			(net "GND")
		)
	)
	(footprint ""
		(layer "F.Cu")
		(at 68.98132 -394.5382 -90)
		(property "Reference" "R711"
			(at 0 0 270)
			(layer "F.SilkS")
			(hide yes)
			(effects
				(font
					(size 1.27 1.27)
				)
			)
		)
		(property "Value" ""
			(at 0 0 270)
			(layer "F.Fab")
			(effects
				(font
					(size 1.27 1.27)
				)
			)
		)
		(duplicate_pad_numbers_are_jumpers no)
		(fp_line
			(start -0.32512 0.175006)
			(end -0.32512 -0.175006)
			(stroke
				(width 0.1)
				(type default)
			)
			(layer "F.Fab")
		)
		(fp_line
			(start 0.32512 0.175006)
			(end -0.32512 0.175006)
			(stroke
				(width 0.1)
				(type default)
			)
			(layer "F.Fab")
		)
		(fp_line
			(start -0.32512 -0.175006)
			(end 0.32512 -0.175006)
			(stroke
				(width 0.1)
				(type default)
			)
			(layer "F.Fab")
		)
		(fp_line
			(start 0.32512 -0.175006)
			(end 0.32512 0.175006)
			(stroke
				(width 0.1)
				(type default)
			)
			(layer "F.Fab")
		)
		(pad "1" smd rect
			(at -0.2667 0 270)
			(size 0.3048 0.381)
			(layers "F.Cu" "F.Mask" "F.Paste")
			(net "NCF_A1_CPU1_P0_GND")
		)
		(pad "2" smd rect
			(at 0.2667 0 90)
			(size 0.3048 0.381)
			(layers "F.Cu" "F.Mask" "F.Paste")
			(net "GND")
		)
	)
	(footprint ""
		(layer "F.Cu")
		(at 138.067542 -381.7874)
		(property "Reference" "R1433"
			(at 0 0 0)
			(layer "F.SilkS")
			(hide yes)
			(effects
				(font
					(size 1.27 1.27)
				)
			)
		)
		(property "Value" ""
			(at 0 0 0)
			(layer "F.Fab")
			(effects
				(font
					(size 1.27 1.27)
				)
			)
		)
		(duplicate_pad_numbers_are_jumpers no)
		(fp_line
			(start -0.32512 -0.175006)
			(end 0.32512 -0.175006)
			(stroke
				(width 0.1)
				(type default)
			)
			(layer "F.Fab")
		)
		(fp_line
			(start -0.32512 0.175006)
			(end -0.32512 -0.175006)
			(stroke
				(width 0.1)
				(type default)
			)
			(layer "F.Fab")
		)
		(fp_line
			(start 0.32512 -0.175006)
			(end 0.32512 0.175006)
			(stroke
				(width 0.1)
				(type default)
			)
			(layer "F.Fab")
		)
		(fp_line
			(start 0.32512 0.175006)
			(end -0.32512 0.175006)
			(stroke
				(width 0.1)
				(type default)
			)
			(layer "F.Fab")
		)
		(pad "1" smd rect
			(at -0.2667 0)
			(size 0.3048 0.381)
			(layers "F.Cu" "F.Mask" "F.Paste")
			(net "CLKREQ_RT_CPU1_P3_N")
		)
		(pad "2" smd rect
			(at 0.2667 0 180)
			(size 0.3048 0.381)
			(layers "F.Cu" "F.Mask" "F.Paste")
			(net "GND")
		)
	)
	(footprint ""
		(layer "F.Cu")
		(at 124.840238 -43.59275)
		(property "Reference" "R6278"
			(at 0 0 0)
			(layer "F.SilkS")
			(hide yes)
			(effects
				(font
					(size 1.27 1.27)
				)
			)
		)
		(property "Value" ""
			(at 0 0 0)
			(layer "F.Fab")
			(effects
				(font
					(size 1.27 1.27)
				)
			)
		)
		(duplicate_pad_numbers_are_jumpers no)
		(fp_line
			(start -0.7874 -0.4064)
			(end 0.7874 -0.4064)
			(stroke
				(width 0.1524)
				(type default)
			)
			(layer "F.SilkS")
		)
		(fp_line
			(start -0.7874 0.4064)
			(end -0.7874 -0.4064)
			(stroke
				(width 0.1524)
				(type default)
			)
			(layer "F.SilkS")
		)
		(fp_line
			(start 0.7874 -0.4064)
			(end 0.7874 0.4064)
			(stroke
				(width 0.1524)
				(type default)
			)
			(layer "F.SilkS")
		)
		(fp_line
			(start 0.7874 0.4064)
			(end -0.7874 0.4064)
			(stroke
				(width 0.1524)
				(type default)
			)
			(layer "F.SilkS")
		)
		(fp_line
			(start -0.67945 -0.305054)
			(end -0.12065 -0.305054)
			(stroke
				(width 0.1)
				(type default)
			)
			(layer "F.Fab")
		)
		(fp_line
			(start -0.67945 0.3048)
			(end -0.67945 -0.305054)
			(stroke
				(width 0.1)
				(type default)
			)
			(layer "F.Fab")
		)
		(fp_line
			(start -0.12065 -0.305054)
			(end -0.12065 -0.2794)
			(stroke
				(width 0.1)
				(type default)
			)
			(layer "F.Fab")
		)
		(fp_line
			(start -0.12065 -0.2794)
			(end 0.12065 -0.2794)
			(stroke
				(width 0.1)
				(type default)
			)
			(layer "F.Fab")
		)
		(fp_line
			(start -0.12065 0.2794)
			(end -0.12065 0.3048)
			(stroke
				(width 0.1)
				(type default)
			)
			(layer "F.Fab")
		)
		(fp_line
			(start -0.12065 0.3048)
			(end -0.67945 0.3048)
			(stroke
				(width 0.1)
				(type default)
			)
			(layer "F.Fab")
		)
		(fp_line
			(start 0.120396 0.2794)
			(end -0.12065 0.2794)
			(stroke
				(width 0.1)
				(type default)
			)
			(layer "F.Fab")
		)
		(fp_line
			(start 0.120396 0.3048)
			(end 0.120396 0.2794)
			(stroke
				(width 0.1)
				(type default)
			)
			(layer "F.Fab")
		)
		(fp_line
			(start 0.12065 -0.3048)
			(end 0.67945 -0.3048)
			(stroke
				(width 0.1)
				(type default)
			)
			(layer "F.Fab")
		)
		(fp_line
			(start 0.12065 -0.2794)
			(end 0.12065 -0.3048)
			(stroke
				(width 0.1)
				(type default)
			)
			(layer "F.Fab")
		)
		(fp_line
			(start 0.67945 -0.3048)
			(end 0.67945 0.3048)
			(stroke
				(width 0.1)
				(type default)
			)
			(layer "F.Fab")
		)
		(fp_line
			(start 0.67945 0.3048)
			(end 0.120396 0.3048)
			(stroke
				(width 0.1)
				(type default)
			)
			(layer "F.Fab")
		)
		(pad "1" smd circle
			(at -0.40005 0)
			(size 0 0)
			(layers "F.Cu" "F.Mask" "F.Paste")
			(net "USB_HUB2_MRP_PRT_CTL4_GANGPWR")
		)
		(pad "2" smd circle
			(at 0.40005 0)
			(size 0 0)
			(layers "F.Cu" "F.Mask" "F.Paste")
			(net "GND")
		)
	)
	(footprint ""
		(layer "F.Cu")
		(at 413.273748 -16.100298 90)
		(property "Reference" "C1565"
			(at 0 0 90)
			(layer "F.SilkS")
			(hide yes)
			(effects
				(font
					(size 1.27 1.27)
				)
			)
		)
		(property "Value" ""
			(at 0 0 90)
			(layer "F.Fab")
			(effects
				(font
					(size 1.27 1.27)
				)
			)
		)
		(duplicate_pad_numbers_are_jumpers no)
		(fp_line
			(start 0.299974 -0.150114)
			(end 0.299974 0.150114)
			(stroke
				(width 0.1)
				(type default)
			)
			(layer "F.Fab")
		)
		(fp_line
			(start -0.299974 -0.150114)
			(end 0.299974 -0.150114)
			(stroke
				(width 0.1)
				(type default)
			)
			(layer "F.Fab")
		)
		(fp_line
			(start 0.299974 0.150114)
			(end -0.299974 0.150114)
			(stroke
				(width 0.1)
				(type default)
			)
			(layer "F.Fab")
		)
		(fp_line
			(start -0.299974 0.150114)
			(end -0.299974 -0.150114)
			(stroke
				(width 0.1)
				(type default)
			)
			(layer "F.Fab")
		)
		(pad "1" smd rect
			(at -0.2667 0 90)
			(size 0.3048 0.381)
			(layers "F.Cu" "F.Mask" "F.Paste")
			(net "P5E_CPU0_G3_TX_C_DP<7>")
		)
		(pad "2" smd rect
			(at 0.2667 0 90)
			(size 0.3048 0.381)
			(layers "F.Cu" "F.Mask" "F.Paste")
			(net "P5E_CPU0_G3_TX_DP<7>")
		)
	)
	(footprint ""
		(layer "F.Cu")
		(at 195.961 -100.294948 90)
		(property "Reference" "R2261"
			(at 0 0 90)
			(layer "F.SilkS")
			(hide yes)
			(effects
				(font
					(size 1.27 1.27)
				)
			)
		)
		(property "Value" ""
			(at 0 0 90)
			(layer "F.Fab")
			(effects
				(font
					(size 1.27 1.27)
				)
			)
		)
		(duplicate_pad_numbers_are_jumpers no)
		(fp_line
			(start 0.7874 -0.4064)
			(end 0.7874 0.4064)
			(stroke
				(width 0.1524)
				(type default)
			)
			(layer "F.SilkS")
		)
		(fp_line
			(start -0.7874 -0.4064)
			(end 0.7874 -0.4064)
			(stroke
				(width 0.1524)
				(type default)
			)
			(layer "F.SilkS")
		)
		(fp_line
			(start 0.7874 0.4064)
			(end -0.7874 0.4064)
			(stroke
				(width 0.1524)
				(type default)
			)
			(layer "F.SilkS")
		)
		(fp_line
			(start -0.7874 0.4064)
			(end -0.7874 -0.4064)
			(stroke
				(width 0.1524)
				(type default)
			)
			(layer "F.SilkS")
		)
		(fp_line
			(start -0.12065 -0.305054)
			(end -0.12065 -0.2794)
			(stroke
				(width 0.1)
				(type default)
			)
			(layer "F.Fab")
		)
		(fp_line
			(start -0.67945 -0.305054)
			(end -0.12065 -0.305054)
			(stroke
				(width 0.1)
				(type default)
			)
			(layer "F.Fab")
		)
		(fp_line
			(start 0.67945 -0.3048)
			(end 0.67945 0.3048)
			(stroke
				(width 0.1)
				(type default)
			)
			(layer "F.Fab")
		)
		(fp_line
			(start 0.12065 -0.3048)
			(end 0.67945 -0.3048)
			(stroke
				(width 0.1)
				(type default)
			)
			(layer "F.Fab")
		)
		(fp_line
			(start 0.12065 -0.2794)
			(end 0.12065 -0.3048)
			(stroke
				(width 0.1)
				(type default)
			)
			(layer "F.Fab")
		)
		(fp_line
			(start -0.12065 -0.2794)
			(end 0.12065 -0.2794)
			(stroke
				(width 0.1)
				(type default)
			)
			(layer "F.Fab")
		)
		(fp_line
			(start 0.120396 0.2794)
			(end -0.12065 0.2794)
			(stroke
				(width 0.1)
				(type default)
			)
			(layer "F.Fab")
		)
		(fp_line
			(start -0.12065 0.2794)
			(end -0.12065 0.3048)
			(stroke
				(width 0.1)
				(type default)
			)
			(layer "F.Fab")
		)
		(fp_line
			(start 0.67945 0.3048)
			(end 0.120396 0.3048)
			(stroke
				(width 0.1)
				(type default)
			)
			(layer "F.Fab")
		)
		(fp_line
			(start 0.120396 0.3048)
			(end 0.120396 0.2794)
			(stroke
				(width 0.1)
				(type default)
			)
			(layer "F.Fab")
		)
		(fp_line
			(start -0.12065 0.3048)
			(end -0.67945 0.3048)
			(stroke
				(width 0.1)
				(type default)
			)
			(layer "F.Fab")
		)
		(fp_line
			(start -0.67945 0.3048)
			(end -0.67945 -0.305054)
			(stroke
				(width 0.1)
				(type default)
			)
			(layer "F.Fab")
		)
		(pad "1" smd circle
			(at -0.40005 0 90)
			(size 0 0)
			(layers "F.Cu" "F.Mask" "F.Paste")
			(net "FM_SWB_PWR_EN_R")
		)
		(pad "2" smd circle
			(at 0.40005 0 90)
			(size 0 0)
			(layers "F.Cu" "F.Mask" "F.Paste")
			(net "FM_SWB_PWR_EN")
		)
	)
	(footprint ""
		(layer "F.Cu")
		(at 191.52362 -422.804082 90)
		(property "Reference" "R2944"
			(at 0 0 90)
			(layer "F.SilkS")
			(hide yes)
			(effects
				(font
					(size 1.27 1.27)
				)
			)
		)
		(property "Value" ""
			(at 0 0 90)
			(layer "F.Fab")
			(effects
				(font
					(size 1.27 1.27)
				)
			)
		)
		(duplicate_pad_numbers_are_jumpers no)
		(fp_line
			(start 0.7874 -0.4064)
			(end 0.7874 0.4064)
			(stroke
				(width 0.1524)
				(type default)
			)
			(layer "F.SilkS")
		)
		(fp_line
			(start -0.7874 -0.4064)
			(end 0.7874 -0.4064)
			(stroke
				(width 0.1524)
				(type default)
			)
			(layer "F.SilkS")
		)
		(fp_line
			(start 0.7874 0.4064)
			(end -0.7874 0.4064)
			(stroke
				(width 0.1524)
				(type default)
			)
			(layer "F.SilkS")
		)
		(fp_line
			(start -0.7874 0.4064)
			(end -0.7874 -0.4064)
			(stroke
				(width 0.1524)
				(type default)
			)
			(layer "F.SilkS")
		)
		(fp_line
			(start -0.12065 -0.305054)
			(end -0.12065 -0.2794)
			(stroke
				(width 0.1)
				(type default)
			)
			(layer "F.Fab")
		)
		(fp_line
			(start -0.67945 -0.305054)
			(end -0.12065 -0.305054)
			(stroke
				(width 0.1)
				(type default)
			)
			(layer "F.Fab")
		)
		(fp_line
			(start 0.67945 -0.3048)
			(end 0.67945 0.3048)
			(stroke
				(width 0.1)
				(type default)
			)
			(layer "F.Fab")
		)
		(fp_line
			(start 0.12065 -0.3048)
			(end 0.67945 -0.3048)
			(stroke
				(width 0.1)
				(type default)
			)
			(layer "F.Fab")
		)
		(fp_line
			(start 0.12065 -0.2794)
			(end 0.12065 -0.3048)
			(stroke
				(width 0.1)
				(type default)
			)
			(layer "F.Fab")
		)
		(fp_line
			(start -0.12065 -0.2794)
			(end 0.12065 -0.2794)
			(stroke
				(width 0.1)
				(type default)
			)
			(layer "F.Fab")
		)
		(fp_line
			(start 0.120396 0.2794)
			(end -0.12065 0.2794)
			(stroke
				(width 0.1)
				(type default)
			)
			(layer "F.Fab")
		)
		(fp_line
			(start -0.12065 0.2794)
			(end -0.12065 0.3048)
			(stroke
				(width 0.1)
				(type default)
			)
			(layer "F.Fab")
		)
		(fp_line
			(start 0.67945 0.3048)
			(end 0.120396 0.3048)
			(stroke
				(width 0.1)
				(type default)
			)
			(layer "F.Fab")
		)
		(fp_line
			(start 0.120396 0.3048)
			(end 0.120396 0.2794)
			(stroke
				(width 0.1)
				(type default)
			)
			(layer "F.Fab")
		)
		(fp_line
			(start -0.12065 0.3048)
			(end -0.67945 0.3048)
			(stroke
				(width 0.1)
				(type default)
			)
			(layer "F.Fab")
		)
		(fp_line
			(start -0.67945 0.3048)
			(end -0.67945 -0.305054)
			(stroke
				(width 0.1)
				(type default)
			)
			(layer "F.Fab")
		)
		(pad "1" smd circle
			(at -0.40005 0 90)
			(size 0 0)
			(layers "F.Cu" "F.Mask" "F.Paste")
			(net "FM_GPU_HSC_EN_BUF_R")
		)
		(pad "2" smd circle
			(at 0.40005 0 90)
			(size 0 0)
			(layers "F.Cu" "F.Mask" "F.Paste")
			(net "FM_GPU_HSC_EN_BUF")
		)
	)
	(footprint ""
		(layer "F.Cu")
		(at 175.961294 -332.734412 -90)
		(property "Reference" "PC803"
			(at -4.13512 4.721352 90)
			(unlocked yes)
			(layer "F.SilkS")
			(effects
				(font
					(size 0.7874 0.5842)
					(thickness 0.1524)
				)
				(justify left)
			)
		)
		(property "Value" ""
			(at 0 0 270)
			(layer "F.Fab")
			(effects
				(font
					(size 1.27 1.27)
				)
			)
		)
		(duplicate_pad_numbers_are_jumpers no)
		(fp_line
			(start -1.988058 2.750058)
			(end 2.750058 2.750058)
			(stroke
				(width 0.1524)
				(type default)
			)
			(layer "F.SilkS")
		)
		(fp_line
			(start 2.750058 2.750058)
			(end 2.750058 0.9398)
			(stroke
				(width 0.1524)
				(type default)
			)
			(layer "F.SilkS")
		)
		(fp_line
			(start -2.750058 1.988058)
			(end -1.988058 2.750058)
			(stroke
				(width 0.1524)
				(type default)
			)
			(layer "F.SilkS")
		)
		(fp_line
			(start -2.750058 0.9398)
			(end -2.750058 1.988058)
			(stroke
				(width 0.1524)
				(type default)
			)
			(layer "F.SilkS")
		)
		(fp_line
			(start 2.750058 -0.9398)
			(end 2.750058 -2.750058)
			(stroke
				(width 0.1524)
				(type default)
			)
			(layer "F.SilkS")
		)
		(fp_line
			(start -2.750058 -1.988058)
			(end -2.750058 -0.9398)
			(stroke
				(width 0.1524)
				(type default)
			)
			(layer "F.SilkS")
		)
		(fp_line
			(start -1.988058 -2.750058)
			(end -2.750058 -1.988058)
			(stroke
				(width 0.1524)
				(type default)
			)
			(layer "F.SilkS")
		)
		(fp_line
			(start 2.750058 -2.750058)
			(end -1.988058 -2.750058)
			(stroke
				(width 0.1524)
				(type default)
			)
			(layer "F.SilkS")
		)
		(fp_line
			(start -2.750058 2.750058)
			(end 2.750058 2.750058)
			(stroke
				(width 0.1)
				(type default)
			)
			(layer "F.Fab")
		)
		(fp_line
			(start 2.750058 2.750058)
			(end 2.750058 -2.750058)
			(stroke
				(width 0.1)
				(type default)
			)
			(layer "F.Fab")
		)
		(fp_line
			(start -2.750058 -2.750058)
			(end -2.750058 2.750058)
			(stroke
				(width 0.1)
				(type default)
			)
			(layer "F.Fab")
		)
		(fp_line
			(start 2.750058 -2.750058)
			(end -2.750058 -2.750058)
			(stroke
				(width 0.1)
				(type default)
			)
			(layer "F.Fab")
		)
		(pad "1" smd rect
			(at -2.199894 0)
			(size 1.6002 3.0226)
			(layers "F.Cu" "F.Mask" "F.Paste")
			(net "PVDD11_S3_P1")
		)
		(pad "2" smd rect
			(at 2.199894 0)
			(size 1.6002 3.0226)
			(layers "F.Cu" "F.Mask" "F.Paste")
			(net "GND")
		)
	)
)
